(kicad_pcb
	(version 20260206)
	(generator "pcbnew")
	(generator_version "10.0")
	(general
		(thickness 1.6)
		(legacy_teardrops no)
	)
	(paper "A4")
	(title_block
		(title "04192023_DAF0TMB3IC0_F0TG_MB_C_brd_V02_OCP.brd")
		(comment 1 "Grand Teton / footprints 7791-7798 of 8354")
	)
	(layers
		(0 "F.Cu" signal "TOP")
		(4 "In1.Cu" signal "GND")
		(6 "In2.Cu" signal "IN1")
		(8 "In3.Cu" signal "GND1")
		(10 "In4.Cu" signal "IN2")
		(12 "In5.Cu" signal "GND2")
		(14 "In6.Cu" signal "IN3")
		(16 "In7.Cu" signal "GND3")
		(18 "In8.Cu" signal "VCC")
		(20 "In9.Cu" signal "VCC1")
		(22 "In10.Cu" signal "GND4")
		(24 "In11.Cu" signal "IN4")
		(26 "In12.Cu" signal "GND5")
		(28 "In13.Cu" signal "IN5")
		(30 "In14.Cu" signal "GND6")
		(32 "In15.Cu" signal "IN6")
		(34 "In16.Cu" signal "GND7")
		(2 "B.Cu" signal "BOTTOM")
		(9 "F.Adhes" user "F.Adhesive")
		(11 "B.Adhes" user "B.Adhesive")
		(13 "F.Paste" user "Package Geometry/Pastemask Top")
		(15 "B.Paste" user "Package Geometry/Pastemask Bottom")
		(5 "F.SilkS" user "Ref Des/Silkscreen Top")
		(7 "B.SilkS" user "Ref Des/Silkscreen Bottom")
		(1 "F.Mask" user "Board Geometry/Soldermask Top")
		(3 "B.Mask" user "Board Geometry/Soldermask Bottom")
		(17 "Dwgs.User" user "User.Drawings")
		(19 "Cmts.User" user "User.Comments")
		(21 "Eco1.User" user "User.Eco1")
		(23 "Eco2.User" user "User.Eco2")
		(25 "Edge.Cuts" user "Board Geometry/Outline")
		(27 "Margin" user)
		(31 "F.CrtYd" user "Package Geometry/Place Bound Top")
		(29 "B.CrtYd" user "Package Geometry/Place Bound Bottom")
		(35 "F.Fab" user "Ref Des/Assembly Top")
		(33 "B.Fab" user "Ref Des/Assembly Bottom")
	)
	(footprint ""
		(layer "B.Cu")
		(at 320.19113 -398.942052 90)
		(property "Reference" "C571"
			(at 0 0 90)
			(layer "B.SilkS")
			(hide yes)
			(effects
				(font
					(size 1.27 1.27)
				)
				(justify mirror)
			)
		)
		(property "Value" ""
			(at 0 0 90)
			(layer "B.Fab")
			(effects
				(font
					(size 1.27 1.27)
				)
				(justify mirror)
			)
		)
		(duplicate_pad_numbers_are_jumpers no)
		(fp_line
			(start 0.7874 -0.4064)
			(end -0.7874 -0.4064)
			(stroke
				(width 0.1524)
				(type default)
			)
			(layer "B.SilkS")
		)
		(fp_line
			(start -0.7874 -0.4064)
			(end -0.7874 0.4064)
			(stroke
				(width 0.1524)
				(type default)
			)
			(layer "B.SilkS")
		)
		(fp_line
			(start 0.7874 0.4064)
			(end 0.7874 -0.4064)
			(stroke
				(width 0.1524)
				(type default)
			)
			(layer "B.SilkS")
		)
		(fp_line
			(start -0.7874 0.4064)
			(end 0.7874 0.4064)
			(stroke
				(width 0.1524)
				(type default)
			)
			(layer "B.SilkS")
		)
		(fp_line
			(start 0.67945 -0.305054)
			(end 0.12065 -0.305054)
			(stroke
				(width 0.1)
				(type default)
			)
			(layer "B.Fab")
		)
		(fp_line
			(start 0.12065 -0.305054)
			(end 0.12065 -0.2794)
			(stroke
				(width 0.1)
				(type default)
			)
			(layer "B.Fab")
		)
		(fp_line
			(start -0.12065 -0.3048)
			(end -0.67945 -0.3048)
			(stroke
				(width 0.1)
				(type default)
			)
			(layer "B.Fab")
		)
		(fp_line
			(start -0.67945 -0.3048)
			(end -0.67945 0.3048)
			(stroke
				(width 0.1)
				(type default)
			)
			(layer "B.Fab")
		)
		(fp_line
			(start 0.12065 -0.2794)
			(end -0.12065 -0.2794)
			(stroke
				(width 0.1)
				(type default)
			)
			(layer "B.Fab")
		)
		(fp_line
			(start -0.12065 -0.2794)
			(end -0.12065 -0.3048)
			(stroke
				(width 0.1)
				(type default)
			)
			(layer "B.Fab")
		)
		(fp_line
			(start 0.12065 0.2794)
			(end 0.12065 0.3048)
			(stroke
				(width 0.1)
				(type default)
			)
			(layer "B.Fab")
		)
		(fp_line
			(start -0.120396 0.2794)
			(end 0.12065 0.2794)
			(stroke
				(width 0.1)
				(type default)
			)
			(layer "B.Fab")
		)
		(fp_line
			(start 0.67945 0.3048)
			(end 0.67945 -0.305054)
			(stroke
				(width 0.1)
				(type default)
			)
			(layer "B.Fab")
		)
		(fp_line
			(start 0.12065 0.3048)
			(end 0.67945 0.3048)
			(stroke
				(width 0.1)
				(type default)
			)
			(layer "B.Fab")
		)
		(fp_line
			(start -0.120396 0.3048)
			(end -0.120396 0.2794)
			(stroke
				(width 0.1)
				(type default)
			)
			(layer "B.Fab")
		)
		(fp_line
			(start -0.67945 0.3048)
			(end -0.120396 0.3048)
			(stroke
				(width 0.1)
				(type default)
			)
			(layer "B.Fab")
		)
		(pad "1" smd circle
			(at 0.40005 0 270)
			(size 0 0)
			(layers "B.Cu" "B.Mask" "B.Paste")
			(net "P0V9_CPU0_RT0_2A")
		)
		(pad "2" smd circle
			(at -0.40005 0 270)
			(size 0 0)
			(layers "B.Cu" "B.Mask" "B.Paste")
			(net "GND")
		)
	)
	(footprint ""
		(layer "B.Cu")
		(at 367.102898 -215.303608 180)
		(property "Reference" "PR302"
			(at 0 0 0)
			(layer "B.SilkS")
			(hide yes)
			(effects
				(font
					(size 1.27 1.27)
				)
				(justify mirror)
			)
		)
		(property "Value" ""
			(at 0 0 0)
			(layer "B.Fab")
			(effects
				(font
					(size 1.27 1.27)
				)
				(justify mirror)
			)
		)
		(duplicate_pad_numbers_are_jumpers no)
		(fp_line
			(start 0.7874 0.4064)
			(end 0.7874 -0.4064)
			(stroke
				(width 0.1524)
				(type default)
			)
			(layer "B.SilkS")
		)
		(fp_line
			(start 0.7874 -0.4064)
			(end -0.7874 -0.4064)
			(stroke
				(width 0.1524)
				(type default)
			)
			(layer "B.SilkS")
		)
		(fp_line
			(start -0.7874 0.4064)
			(end 0.7874 0.4064)
			(stroke
				(width 0.1524)
				(type default)
			)
			(layer "B.SilkS")
		)
		(fp_line
			(start -0.7874 -0.4064)
			(end -0.7874 0.4064)
			(stroke
				(width 0.1524)
				(type default)
			)
			(layer "B.SilkS")
		)
		(fp_line
			(start 0.67945 0.3048)
			(end 0.67945 -0.305054)
			(stroke
				(width 0.1)
				(type default)
			)
			(layer "B.Fab")
		)
		(fp_line
			(start 0.67945 -0.305054)
			(end 0.12065 -0.305054)
			(stroke
				(width 0.1)
				(type default)
			)
			(layer "B.Fab")
		)
		(fp_line
			(start 0.12065 0.3048)
			(end 0.67945 0.3048)
			(stroke
				(width 0.1)
				(type default)
			)
			(layer "B.Fab")
		)
		(fp_line
			(start 0.12065 0.2794)
			(end 0.12065 0.3048)
			(stroke
				(width 0.1)
				(type default)
			)
			(layer "B.Fab")
		)
		(fp_line
			(start 0.12065 -0.2794)
			(end -0.12065 -0.2794)
			(stroke
				(width 0.1)
				(type default)
			)
			(layer "B.Fab")
		)
		(fp_line
			(start 0.12065 -0.305054)
			(end 0.12065 -0.2794)
			(stroke
				(width 0.1)
				(type default)
			)
			(layer "B.Fab")
		)
		(fp_line
			(start -0.120396 0.3048)
			(end -0.120396 0.2794)
			(stroke
				(width 0.1)
				(type default)
			)
			(layer "B.Fab")
		)
		(fp_line
			(start -0.120396 0.2794)
			(end 0.12065 0.2794)
			(stroke
				(width 0.1)
				(type default)
			)
			(layer "B.Fab")
		)
		(fp_line
			(start -0.12065 -0.2794)
			(end -0.12065 -0.3048)
			(stroke
				(width 0.1)
				(type default)
			)
			(layer "B.Fab")
		)
		(fp_line
			(start -0.12065 -0.3048)
			(end -0.67945 -0.3048)
			(stroke
				(width 0.1)
				(type default)
			)
			(layer "B.Fab")
		)
		(fp_line
			(start -0.67945 0.3048)
			(end -0.120396 0.3048)
			(stroke
				(width 0.1)
				(type default)
			)
			(layer "B.Fab")
		)
		(fp_line
			(start -0.67945 -0.3048)
			(end -0.67945 0.3048)
			(stroke
				(width 0.1)
				(type default)
			)
			(layer "B.Fab")
		)
		(pad "1" smd circle
			(at 0.40005 0)
			(size 0 0)
			(layers "B.Cu" "B.Mask" "B.Paste")
			(net "SVID_PVDDCR_CPU0_P0_SVC_R")
		)
		(pad "2" smd circle
			(at -0.40005 0)
			(size 0 0)
			(layers "B.Cu" "B.Mask" "B.Paste")
			(net "SVID_PVDDCR_CPU0_P0_SVC")
		)
	)
	(footprint ""
		(layer "B.Cu")
		(at 311.427876 -78.775814 -90)
		(property "Reference" "R9446"
			(at 0 0 90)
			(layer "B.SilkS")
			(hide yes)
			(effects
				(font
					(size 1.27 1.27)
				)
				(justify mirror)
			)
		)
		(property "Value" ""
			(at 0 0 90)
			(layer "B.Fab")
			(effects
				(font
					(size 1.27 1.27)
				)
				(justify mirror)
			)
		)
		(duplicate_pad_numbers_are_jumpers no)
		(fp_line
			(start -0.7874 0.4064)
			(end 0.7874 0.4064)
			(stroke
				(width 0.1524)
				(type default)
			)
			(layer "B.SilkS")
		)
		(fp_line
			(start 0.7874 0.4064)
			(end 0.7874 -0.4064)
			(stroke
				(width 0.1524)
				(type default)
			)
			(layer "B.SilkS")
		)
		(fp_line
			(start -0.7874 -0.4064)
			(end -0.7874 0.4064)
			(stroke
				(width 0.1524)
				(type default)
			)
			(layer "B.SilkS")
		)
		(fp_line
			(start 0.7874 -0.4064)
			(end -0.7874 -0.4064)
			(stroke
				(width 0.1524)
				(type default)
			)
			(layer "B.SilkS")
		)
		(fp_line
			(start -0.67945 0.3048)
			(end -0.120396 0.3048)
			(stroke
				(width 0.1)
				(type default)
			)
			(layer "B.Fab")
		)
		(fp_line
			(start -0.120396 0.3048)
			(end -0.120396 0.2794)
			(stroke
				(width 0.1)
				(type default)
			)
			(layer "B.Fab")
		)
		(fp_line
			(start 0.12065 0.3048)
			(end 0.67945 0.3048)
			(stroke
				(width 0.1)
				(type default)
			)
			(layer "B.Fab")
		)
		(fp_line
			(start 0.67945 0.3048)
			(end 0.67945 -0.305054)
			(stroke
				(width 0.1)
				(type default)
			)
			(layer "B.Fab")
		)
		(fp_line
			(start -0.120396 0.2794)
			(end 0.12065 0.2794)
			(stroke
				(width 0.1)
				(type default)
			)
			(layer "B.Fab")
		)
		(fp_line
			(start 0.12065 0.2794)
			(end 0.12065 0.3048)
			(stroke
				(width 0.1)
				(type default)
			)
			(layer "B.Fab")
		)
		(fp_line
			(start -0.12065 -0.2794)
			(end -0.12065 -0.3048)
			(stroke
				(width 0.1)
				(type default)
			)
			(layer "B.Fab")
		)
		(fp_line
			(start 0.12065 -0.2794)
			(end -0.12065 -0.2794)
			(stroke
				(width 0.1)
				(type default)
			)
			(layer "B.Fab")
		)
		(fp_line
			(start -0.67945 -0.3048)
			(end -0.67945 0.3048)
			(stroke
				(width 0.1)
				(type default)
			)
			(layer "B.Fab")
		)
		(fp_line
			(start -0.12065 -0.3048)
			(end -0.67945 -0.3048)
			(stroke
				(width 0.1)
				(type default)
			)
			(layer "B.Fab")
		)
		(fp_line
			(start 0.12065 -0.305054)
			(end 0.12065 -0.2794)
			(stroke
				(width 0.1)
				(type default)
			)
			(layer "B.Fab")
		)
		(fp_line
			(start 0.67945 -0.305054)
			(end 0.12065 -0.305054)
			(stroke
				(width 0.1)
				(type default)
			)
			(layer "B.Fab")
		)
		(pad "1" smd circle
			(at 0.40005 0 90)
			(size 0 0)
			(layers "B.Cu" "B.Mask" "B.Paste")
			(net "PWRGD_PS_PWROK_PLD_ISO")
		)
		(pad "2" smd circle
			(at -0.40005 0 90)
			(size 0 0)
			(layers "B.Cu" "B.Mask" "B.Paste")
			(net "PWRGD_PS_PWROK_PLD_ISO_R")
		)
	)
	(footprint ""
		(layer "B.Cu")
		(at 70.743064 -408.517344 90)
		(property "Reference" "C6676"
			(at 0 0 90)
			(layer "B.SilkS")
			(hide yes)
			(effects
				(font
					(size 1.27 1.27)
				)
				(justify mirror)
			)
		)
		(property "Value" ""
			(at 0 0 90)
			(layer "B.Fab")
			(effects
				(font
					(size 1.27 1.27)
				)
				(justify mirror)
			)
		)
		(duplicate_pad_numbers_are_jumpers no)
		(fp_line
			(start 0.299974 -0.150114)
			(end -0.299974 -0.150114)
			(stroke
				(width 0.1)
				(type default)
			)
			(layer "B.Fab")
		)
		(fp_line
			(start -0.299974 -0.150114)
			(end -0.299974 0.150114)
			(stroke
				(width 0.1)
				(type default)
			)
			(layer "B.Fab")
		)
		(fp_line
			(start 0.299974 0.150114)
			(end 0.299974 -0.150114)
			(stroke
				(width 0.1)
				(type default)
			)
			(layer "B.Fab")
		)
		(fp_line
			(start -0.299974 0.150114)
			(end 0.299974 0.150114)
			(stroke
				(width 0.1)
				(type default)
			)
			(layer "B.Fab")
		)
		(pad "1" smd rect
			(at 0.2667 0 270)
			(size 0.3048 0.381)
			(layers "B.Cu" "B.Mask" "B.Paste")
			(net "P5E_CPU1_P1_TX_BUF_C_DN<7>")
		)
		(pad "2" smd rect
			(at -0.2667 0 270)
			(size 0.3048 0.381)
			(layers "B.Cu" "B.Mask" "B.Paste")
			(net "P5E_CPU1_P1_TX_BUF_DN<7>")
		)
	)
	(footprint ""
		(layer "B.Cu")
		(at 160.346136 -388.011162 -90)
		(property "Reference" "C397"
			(at 0 0 90)
			(layer "B.SilkS")
			(hide yes)
			(effects
				(font
					(size 1.27 1.27)
				)
				(justify mirror)
			)
		)
		(property "Value" ""
			(at 0 0 90)
			(layer "B.Fab")
			(effects
				(font
					(size 1.27 1.27)
				)
				(justify mirror)
			)
		)
		(duplicate_pad_numbers_are_jumpers no)
		(fp_line
			(start -0.299974 0.150114)
			(end 0.299974 0.150114)
			(stroke
				(width 0.1)
				(type default)
			)
			(layer "B.Fab")
		)
		(fp_line
			(start 0.299974 0.150114)
			(end 0.299974 -0.150114)
			(stroke
				(width 0.1)
				(type default)
			)
			(layer "B.Fab")
		)
		(fp_line
			(start -0.299974 -0.150114)
			(end -0.299974 0.150114)
			(stroke
				(width 0.1)
				(type default)
			)
			(layer "B.Fab")
		)
		(fp_line
			(start 0.299974 -0.150114)
			(end -0.299974 -0.150114)
			(stroke
				(width 0.1)
				(type default)
			)
			(layer "B.Fab")
		)
		(pad "1" smd rect
			(at 0.2667 0 90)
			(size 0.3048 0.381)
			(layers "B.Cu" "B.Mask" "B.Paste")
			(net "P0V9_CPU1_RT2_2A_2D")
		)
		(pad "2" smd rect
			(at -0.2667 0 90)
			(size 0.3048 0.381)
			(layers "B.Cu" "B.Mask" "B.Paste")
			(net "GND")
		)
	)
	(footprint ""
		(layer "B.Cu")
		(at 70.0532 -382.8796 180)
		(property "Reference" "R709"
			(at 0 0 0)
			(layer "B.SilkS")
			(hide yes)
			(effects
				(font
					(size 1.27 1.27)
				)
				(justify mirror)
			)
		)
		(property "Value" ""
			(at 0 0 0)
			(layer "B.Fab")
			(effects
				(font
					(size 1.27 1.27)
				)
				(justify mirror)
			)
		)
		(duplicate_pad_numbers_are_jumpers no)
		(fp_line
			(start 0.32512 0.175006)
			(end 0.32512 -0.175006)
			(stroke
				(width 0.1)
				(type default)
			)
			(layer "B.Fab")
		)
		(fp_line
			(start 0.32512 -0.175006)
			(end -0.32512 -0.175006)
			(stroke
				(width 0.1)
				(type default)
			)
			(layer "B.Fab")
		)
		(fp_line
			(start -0.32512 0.175006)
			(end 0.32512 0.175006)
			(stroke
				(width 0.1)
				(type default)
			)
			(layer "B.Fab")
		)
		(fp_line
			(start -0.32512 -0.175006)
			(end -0.32512 0.175006)
			(stroke
				(width 0.1)
				(type default)
			)
			(layer "B.Fab")
		)
		(pad "1" smd rect
			(at 0.2667 0)
			(size 0.3048 0.381)
			(layers "B.Cu" "B.Mask" "B.Paste")
			(net "NCF_CPU1_P0_GND")
		)
		(pad "2" smd rect
			(at -0.2667 0 180)
			(size 0.3048 0.381)
			(layers "B.Cu" "B.Mask" "B.Paste")
			(net "GND")
		)
	)
	(footprint ""
		(layer "B.Cu")
		(at 153.456386 -318.53505 180)
		(property "Reference" "Y5"
			(at -3.805936 0.462026 0)
			(unlocked yes)
			(layer "B.SilkS")
			(effects
				(font
					(size 0.7874 0.5842)
					(thickness 0.1524)
				)
				(justify left mirror)
			)
		)
		(property "Value" ""
			(at 0 0 0)
			(layer "B.Fab")
			(effects
				(font
					(size 1.27 1.27)
				)
				(justify mirror)
			)
		)
		(duplicate_pad_numbers_are_jumpers no)
		(fp_line
			(start 1.905 1.0414)
			(end -1.905 1.0414)
			(stroke
				(width 0.1524)
				(type default)
			)
			(layer "B.SilkS")
		)
		(fp_line
			(start 1.905 -1.0414)
			(end 1.905 1.0414)
			(stroke
				(width 0.1524)
				(type default)
			)
			(layer "B.SilkS")
		)
		(fp_line
			(start -1.905 1.0414)
			(end -1.905 -1.0414)
			(stroke
				(width 0.1524)
				(type default)
			)
			(layer "B.SilkS")
		)
		(fp_line
			(start -1.905 -1.0414)
			(end 1.905 -1.0414)
			(stroke
				(width 0.1524)
				(type default)
			)
			(layer "B.SilkS")
		)
		(fp_line
			(start 1.649984 0.824992)
			(end -1.649984 0.824992)
			(stroke
				(width 0.1)
				(type default)
			)
			(layer "B.Fab")
		)
		(fp_line
			(start 1.649984 -0.824992)
			(end 1.649984 0.824992)
			(stroke
				(width 0.1)
				(type default)
			)
			(layer "B.Fab")
		)
		(fp_line
			(start -1.649984 0.824992)
			(end -1.649984 -0.824992)
			(stroke
				(width 0.1)
				(type default)
			)
			(layer "B.Fab")
		)
		(fp_line
			(start -1.649984 -0.824992)
			(end 1.649984 -0.824992)
			(stroke
				(width 0.1)
				(type default)
			)
			(layer "B.Fab")
		)
		(pad "1" smd rect
			(at 1.249934 0)
			(size 1.016 1.8034)
			(layers "B.Cu" "B.Mask" "B.Paste")
			(net "XTAL_CPU1_R_X32K_X1")
		)
		(pad "2" smd rect
			(at -1.249934 0 180)
			(size 1.016 1.8034)
			(layers "B.Cu" "B.Mask" "B.Paste")
			(net "XTAL_CPU1_R_X32K_X2")
		)
		(zone
			(layer "B.Cu")
			(hatch none 0.5)
			(connect_pads
				(clearance 0)
			)
			(min_thickness 0.25)
			(keepout
				(tracks not_allowed)
				(vias allowed)
				(pads allowed)
				(copperpour not_allowed)
				(footprints allowed)
			)
			(placement
				(enabled no)
				(sheetname "")
			)
			(fill
				(thermal_gap 0.5)
				(thermal_bridge_width 0.5)
				(island_removal_mode 0)
			)
			(polygon
				(pts
					(xy 152.765252 -317.58255) (xy 152.765252 -319.48755) (xy 154.14752 -319.48755) (xy 154.14752 -317.58255)
				)
			)
		)
	)
	(footprint ""
		(layer "B.Cu")
		(at 130.408934 -31.622492 180)
		(property "Reference" "C6064"
			(at 0 0 0)
			(layer "B.SilkS")
			(hide yes)
			(effects
				(font
					(size 1.27 1.27)
				)
				(justify mirror)
			)
		)
		(property "Value" ""
			(at 0 0 0)
			(layer "B.Fab")
			(effects
				(font
					(size 1.27 1.27)
				)
				(justify mirror)
			)
		)
		(duplicate_pad_numbers_are_jumpers no)
		(fp_line
			(start 0.7874 0.4064)
			(end 0.7874 -0.4064)
			(stroke
				(width 0.1524)
				(type default)
			)
			(layer "B.SilkS")
		)
		(fp_line
			(start 0.7874 -0.4064)
			(end -0.7874 -0.4064)
			(stroke
				(width 0.1524)
				(type default)
			)
			(layer "B.SilkS")
		)
		(fp_line
			(start -0.7874 0.4064)
			(end 0.7874 0.4064)
			(stroke
				(width 0.1524)
				(type default)
			)
			(layer "B.SilkS")
		)
		(fp_line
			(start -0.7874 -0.4064)
			(end -0.7874 0.4064)
			(stroke
				(width 0.1524)
				(type default)
			)
			(layer "B.SilkS")
		)
		(fp_line
			(start 0.67945 0.3048)
			(end 0.67945 -0.305054)
			(stroke
				(width 0.1)
				(type default)
			)
			(layer "B.Fab")
		)
		(fp_line
			(start 0.67945 -0.305054)
			(end 0.12065 -0.305054)
			(stroke
				(width 0.1)
				(type default)
			)
			(layer "B.Fab")
		)
		(fp_line
			(start 0.12065 0.3048)
			(end 0.67945 0.3048)
			(stroke
				(width 0.1)
				(type default)
			)
			(layer "B.Fab")
		)
		(fp_line
			(start 0.12065 0.2794)
			(end 0.12065 0.3048)
			(stroke
				(width 0.1)
				(type default)
			)
			(layer "B.Fab")
		)
		(fp_line
			(start 0.12065 -0.2794)
			(end -0.12065 -0.2794)
			(stroke
				(width 0.1)
				(type default)
			)
			(layer "B.Fab")
		)
		(fp_line
			(start 0.12065 -0.305054)
			(end 0.12065 -0.2794)
			(stroke
				(width 0.1)
				(type default)
			)
			(layer "B.Fab")
		)
		(fp_line
			(start -0.120396 0.3048)
			(end -0.120396 0.2794)
			(stroke
				(width 0.1)
				(type default)
			)
			(layer "B.Fab")
		)
		(fp_line
			(start -0.120396 0.2794)
			(end 0.12065 0.2794)
			(stroke
				(width 0.1)
				(type default)
			)
			(layer "B.Fab")
		)
		(fp_line
			(start -0.12065 -0.2794)
			(end -0.12065 -0.3048)
			(stroke
				(width 0.1)
				(type default)
			)
			(layer "B.Fab")
		)
		(fp_line
			(start -0.12065 -0.3048)
			(end -0.67945 -0.3048)
			(stroke
				(width 0.1)
				(type default)
			)
			(layer "B.Fab")
		)
		(fp_line
			(start -0.67945 0.3048)
			(end -0.120396 0.3048)
			(stroke
				(width 0.1)
				(type default)
			)
			(layer "B.Fab")
		)
		(fp_line
			(start -0.67945 -0.3048)
			(end -0.67945 0.3048)
			(stroke
				(width 0.1)
				(type default)
			)
			(layer "B.Fab")
		)
		(pad "1" smd circle
			(at 0.40005 0)
			(size 0 0)
			(layers "B.Cu" "B.Mask" "B.Paste")
			(net "P1V2_AUX")
		)
		(pad "2" smd circle
			(at -0.40005 0)
			(size 0 0)
			(layers "B.Cu" "B.Mask" "B.Paste")
			(net "GND")
		)
	)
)
